(kicad_pcb
	(version 20260206)
	(generator "pcbnew")
	(generator_version "10.0")
	(general
		(thickness 1.6)
		(legacy_teardrops no)
	)
	(paper "A4")
	(title_block
		(title "04192023_DAF0TMB3IC0_F0TG_MB_C_brd_V02_OCP.brd")
		(comment 1 "Grand Teton / footprints 4150-4155 of 8354")
	)
	(layers
		(0 "F.Cu" signal "TOP")
		(4 "In1.Cu" signal "GND")
		(6 "In2.Cu" signal "IN1")
		(8 "In3.Cu" signal "GND1")
		(10 "In4.Cu" signal "IN2")
		(12 "In5.Cu" signal "GND2")
		(14 "In6.Cu" signal "IN3")
		(16 "In7.Cu" signal "GND3")
		(18 "In8.Cu" signal "VCC")
		(20 "In9.Cu" signal "VCC1")
		(22 "In10.Cu" signal "GND4")
		(24 "In11.Cu" signal "IN4")
		(26 "In12.Cu" signal "GND5")
		(28 "In13.Cu" signal "IN5")
		(30 "In14.Cu" signal "GND6")
		(32 "In15.Cu" signal "IN6")
		(34 "In16.Cu" signal "GND7")
		(2 "B.Cu" signal "BOTTOM")
		(9 "F.Adhes" user "F.Adhesive")
		(11 "B.Adhes" user "B.Adhesive")
		(13 "F.Paste" user "Package Geometry/Pastemask Top")
		(15 "B.Paste" user "Package Geometry/Pastemask Bottom")
		(5 "F.SilkS" user "Ref Des/Silkscreen Top")
		(7 "B.SilkS" user "Ref Des/Silkscreen Bottom")
		(1 "F.Mask" user "Board Geometry/Soldermask Top")
		(3 "B.Mask" user "Board Geometry/Soldermask Bottom")
		(17 "Dwgs.User" user "User.Drawings")
		(19 "Cmts.User" user "User.Comments")
		(21 "Eco1.User" user "User.Eco1")
		(23 "Eco2.User" user "User.Eco2")
		(25 "Edge.Cuts" user "Board Geometry/Outline")
		(27 "Margin" user)
		(31 "F.CrtYd" user "Package Geometry/Place Bound Top")
		(29 "B.CrtYd" user "Package Geometry/Place Bound Bottom")
		(35 "F.Fab" user "Ref Des/Assembly Top")
		(33 "B.Fab" user "Ref Des/Assembly Bottom")
	)
	(footprint ""
		(layer "F.Cu")
		(at 187.071 -137.632948 90)
		(property "Reference" "R1552"
			(at 0 0 90)
			(layer "F.SilkS")
			(hide yes)
			(effects
				(font
					(size 1.27 1.27)
				)
			)
		)
		(property "Value" ""
			(at 0 0 90)
			(layer "F.Fab")
			(effects
				(font
					(size 1.27 1.27)
				)
			)
		)
		(duplicate_pad_numbers_are_jumpers no)
		(fp_line
			(start 0.7874 -0.4064)
			(end 0.7874 0.4064)
			(stroke
				(width 0.1524)
				(type default)
			)
			(layer "F.SilkS")
		)
		(fp_line
			(start -0.7874 -0.4064)
			(end 0.7874 -0.4064)
			(stroke
				(width 0.1524)
				(type default)
			)
			(layer "F.SilkS")
		)
		(fp_line
			(start 0.7874 0.4064)
			(end -0.7874 0.4064)
			(stroke
				(width 0.1524)
				(type default)
			)
			(layer "F.SilkS")
		)
		(fp_line
			(start -0.7874 0.4064)
			(end -0.7874 -0.4064)
			(stroke
				(width 0.1524)
				(type default)
			)
			(layer "F.SilkS")
		)
		(fp_line
			(start -0.12065 -0.305054)
			(end -0.12065 -0.2794)
			(stroke
				(width 0.1)
				(type default)
			)
			(layer "F.Fab")
		)
		(fp_line
			(start -0.67945 -0.305054)
			(end -0.12065 -0.305054)
			(stroke
				(width 0.1)
				(type default)
			)
			(layer "F.Fab")
		)
		(fp_line
			(start 0.67945 -0.3048)
			(end 0.67945 0.3048)
			(stroke
				(width 0.1)
				(type default)
			)
			(layer "F.Fab")
		)
		(fp_line
			(start 0.12065 -0.3048)
			(end 0.67945 -0.3048)
			(stroke
				(width 0.1)
				(type default)
			)
			(layer "F.Fab")
		)
		(fp_line
			(start 0.12065 -0.2794)
			(end 0.12065 -0.3048)
			(stroke
				(width 0.1)
				(type default)
			)
			(layer "F.Fab")
		)
		(fp_line
			(start -0.12065 -0.2794)
			(end 0.12065 -0.2794)
			(stroke
				(width 0.1)
				(type default)
			)
			(layer "F.Fab")
		)
		(fp_line
			(start 0.120396 0.2794)
			(end -0.12065 0.2794)
			(stroke
				(width 0.1)
				(type default)
			)
			(layer "F.Fab")
		)
		(fp_line
			(start -0.12065 0.2794)
			(end -0.12065 0.3048)
			(stroke
				(width 0.1)
				(type default)
			)
			(layer "F.Fab")
		)
		(fp_line
			(start 0.67945 0.3048)
			(end 0.120396 0.3048)
			(stroke
				(width 0.1)
				(type default)
			)
			(layer "F.Fab")
		)
		(fp_line
			(start 0.120396 0.3048)
			(end 0.120396 0.2794)
			(stroke
				(width 0.1)
				(type default)
			)
			(layer "F.Fab")
		)
		(fp_line
			(start -0.12065 0.3048)
			(end -0.67945 0.3048)
			(stroke
				(width 0.1)
				(type default)
			)
			(layer "F.Fab")
		)
		(fp_line
			(start -0.67945 0.3048)
			(end -0.67945 -0.305054)
			(stroke
				(width 0.1)
				(type default)
			)
			(layer "F.Fab")
		)
		(pad "1" smd circle
			(at -0.40005 0 90)
			(size 0 0)
			(layers "F.Cu" "F.Mask" "F.Paste")
			(net "ESPI_CPU0_R1_D3")
		)
		(pad "2" smd circle
			(at 0.40005 0 90)
			(size 0 0)
			(layers "F.Cu" "F.Mask" "F.Paste")
			(net "ESPI_CPU0_D3")
		)
	)
	(footprint ""
		(layer "F.Cu")
		(at 146.304762 -41.746424 180)
		(property "Reference" "R2410"
			(at 0 0 180)
			(layer "F.SilkS")
			(hide yes)
			(effects
				(font
					(size 1.27 1.27)
				)
			)
		)
		(property "Value" ""
			(at 0 0 180)
			(layer "F.Fab")
			(effects
				(font
					(size 1.27 1.27)
				)
			)
		)
		(duplicate_pad_numbers_are_jumpers no)
		(fp_line
			(start 0.7874 0.4064)
			(end -0.7874 0.4064)
			(stroke
				(width 0.1524)
				(type default)
			)
			(layer "F.SilkS")
		)
		(fp_line
			(start 0.7874 -0.4064)
			(end 0.7874 0.4064)
			(stroke
				(width 0.1524)
				(type default)
			)
			(layer "F.SilkS")
		)
		(fp_line
			(start -0.7874 0.4064)
			(end -0.7874 -0.4064)
			(stroke
				(width 0.1524)
				(type default)
			)
			(layer "F.SilkS")
		)
		(fp_line
			(start -0.7874 -0.4064)
			(end 0.7874 -0.4064)
			(stroke
				(width 0.1524)
				(type default)
			)
			(layer "F.SilkS")
		)
		(fp_line
			(start 0.67945 0.3048)
			(end 0.120396 0.3048)
			(stroke
				(width 0.1)
				(type default)
			)
			(layer "F.Fab")
		)
		(fp_line
			(start 0.67945 -0.3048)
			(end 0.67945 0.3048)
			(stroke
				(width 0.1)
				(type default)
			)
			(layer "F.Fab")
		)
		(fp_line
			(start 0.12065 -0.2794)
			(end 0.12065 -0.3048)
			(stroke
				(width 0.1)
				(type default)
			)
			(layer "F.Fab")
		)
		(fp_line
			(start 0.12065 -0.3048)
			(end 0.67945 -0.3048)
			(stroke
				(width 0.1)
				(type default)
			)
			(layer "F.Fab")
		)
		(fp_line
			(start 0.120396 0.3048)
			(end 0.120396 0.2794)
			(stroke
				(width 0.1)
				(type default)
			)
			(layer "F.Fab")
		)
		(fp_line
			(start 0.120396 0.2794)
			(end -0.12065 0.2794)
			(stroke
				(width 0.1)
				(type default)
			)
			(layer "F.Fab")
		)
		(fp_line
			(start -0.12065 0.3048)
			(end -0.67945 0.3048)
			(stroke
				(width 0.1)
				(type default)
			)
			(layer "F.Fab")
		)
		(fp_line
			(start -0.12065 0.2794)
			(end -0.12065 0.3048)
			(stroke
				(width 0.1)
				(type default)
			)
			(layer "F.Fab")
		)
		(fp_line
			(start -0.12065 -0.2794)
			(end 0.12065 -0.2794)
			(stroke
				(width 0.1)
				(type default)
			)
			(layer "F.Fab")
		)
		(fp_line
			(start -0.12065 -0.305054)
			(end -0.12065 -0.2794)
			(stroke
				(width 0.1)
				(type default)
			)
			(layer "F.Fab")
		)
		(fp_line
			(start -0.67945 0.3048)
			(end -0.67945 -0.305054)
			(stroke
				(width 0.1)
				(type default)
			)
			(layer "F.Fab")
		)
		(fp_line
			(start -0.67945 -0.305054)
			(end -0.12065 -0.305054)
			(stroke
				(width 0.1)
				(type default)
			)
			(layer "F.Fab")
		)
		(pad "1" smd circle
			(at -0.40005 0 180)
			(size 0 0)
			(layers "F.Cu" "F.Mask" "F.Paste")
			(net "SMB_M2_P1_1V8AUX_SDA_R")
		)
		(pad "2" smd circle
			(at 0.40005 0 180)
			(size 0 0)
			(layers "F.Cu" "F.Mask" "F.Paste")
			(net "SMB_M2_P1_1V8AUX_SDA")
		)
	)
	(footprint ""
		(layer "F.Cu")
		(at 271.330928 -385.27736 90)
		(property "Reference" "PPQ8"
			(at -7.52348 -2.129028 0)
			(unlocked yes)
			(layer "F.SilkS")
			(effects
				(font
					(size 0.7874 0.5842)
					(thickness 0.1524)
				)
				(justify left)
			)
		)
		(property "Value" ""
			(at 0 0 90)
			(layer "F.Fab")
			(effects
				(font
					(size 1.27 1.27)
				)
			)
		)
		(duplicate_pad_numbers_are_jumpers no)
		(fp_line
			(start 2.350008 -2.649982)
			(end 2.350008 -2.4892)
			(stroke
				(width 0.1524)
				(type default)
			)
			(layer "F.SilkS")
		)
		(fp_line
			(start -2.350008 -2.649982)
			(end 2.350008 -2.649982)
			(stroke
				(width 0.1524)
				(type default)
			)
			(layer "F.SilkS")
		)
		(fp_line
			(start -2.350008 -2.4384)
			(end -2.350008 -2.649982)
			(stroke
				(width 0.1524)
				(type default)
			)
			(layer "F.SilkS")
		)
		(fp_line
			(start 2.350008 2.4892)
			(end 2.350008 2.649982)
			(stroke
				(width 0.1524)
				(type default)
			)
			(layer "F.SilkS")
		)
		(fp_line
			(start 2.350008 2.649982)
			(end -2.350008 2.649982)
			(stroke
				(width 0.1524)
				(type default)
			)
			(layer "F.SilkS")
		)
		(fp_line
			(start -2.350008 2.649982)
			(end -2.350008 2.413)
			(stroke
				(width 0.1524)
				(type default)
			)
			(layer "F.SilkS")
		)
		(fp_poly
			(pts
				(xy -3.457448 -3.442462) (xy -2.657602 -3.424174) (xy -3.100324 -2.39268)
			)
			(stroke
				(width 0)
				(type default)
			)
			(fill yes)
			(layer "F.SilkS")
		)
		(fp_line
			(start 2.350008 -2.649982)
			(end 2.350008 2.649982)
			(stroke
				(width 0.1)
				(type default)
			)
			(layer "F.Fab")
		)
		(fp_line
			(start -2.350008 -2.649982)
			(end 2.350008 -2.649982)
			(stroke
				(width 0.1)
				(type default)
			)
			(layer "F.Fab")
		)
		(fp_line
			(start 2.350008 2.649982)
			(end -2.350008 2.649982)
			(stroke
				(width 0.1)
				(type default)
			)
			(layer "F.Fab")
		)
		(fp_line
			(start -2.350008 2.649982)
			(end -2.350008 -2.649982)
			(stroke
				(width 0.1)
				(type default)
			)
			(layer "F.Fab")
		)
		(fp_poly
			(pts
				(xy -3.717544 -1.905) (xy -4.758944 -2.3241) (xy -4.758944 -1.524)
			)
			(stroke
				(width 0)
				(type default)
			)
			(fill yes)
			(layer "F.Fab")
		)
		(pad "1" smd rect
			(at -2.999994 -1.905)
			(size 0.7112 1.1684)
			(layers "F.Cu" "F.Mask" "F.Paste")
			(net "P12V_AUX")
		)
		(pad "2" smd rect
			(at -2.999994 -0.635)
			(size 0.7112 1.1684)
			(layers "F.Cu" "F.Mask" "F.Paste")
			(net "P12V_AUX")
		)
		(pad "3" smd rect
			(at -2.999994 0.635)
			(size 0.7112 1.1684)
			(layers "F.Cu" "F.Mask" "F.Paste")
			(net "P12V_AUX")
		)
		(pad "4" smd rect
			(at -2.999994 1.905)
			(size 0.7112 1.1684)
			(layers "F.Cu" "F.Mask" "F.Paste")
			(net "P12V_HSC_GATE_G4")
		)
		(pad "5" smd circle
			(at 0.925068 0)
			(size 0 0)
			(layers "F.Cu" "F.Mask" "F.Paste")
			(net "P12V_MAIN_R")
		)
		(zone
			(layer "F.Cu")
			(hatch none 0.5)
			(connect_pads
				(clearance 0)
			)
			(min_thickness 0.25)
			(keepout
				(tracks not_allowed)
				(vias allowed)
				(pads allowed)
				(copperpour not_allowed)
				(footprints allowed)
			)
			(placement
				(enabled no)
				(sheetname "")
			)
			(fill
				(thermal_gap 0.5)
				(thermal_bridge_width 0.5)
				(island_removal_mode 0)
			)
			(polygon
				(pts
					(xy 268.689328 -383.7178) (xy 273.972528 -383.7178) (xy 273.972528 -382.92786) (xy 268.689328 -382.92786)
				)
			)
		)
	)
	(footprint ""
		(layer "F.Cu")
		(at 19.241516 -39.926514)
		(property "Reference" "R1310"
			(at 0 0 0)
			(layer "F.SilkS")
			(hide yes)
			(effects
				(font
					(size 1.27 1.27)
				)
			)
		)
		(property "Value" ""
			(at 0 0 0)
			(layer "F.Fab")
			(effects
				(font
					(size 1.27 1.27)
				)
			)
		)
		(duplicate_pad_numbers_are_jumpers no)
		(fp_line
			(start -0.7874 -0.4064)
			(end 0.7874 -0.4064)
			(stroke
				(width 0.1524)
				(type default)
			)
			(layer "F.SilkS")
		)
		(fp_line
			(start -0.7874 0.4064)
			(end -0.7874 -0.4064)
			(stroke
				(width 0.1524)
				(type default)
			)
			(layer "F.SilkS")
		)
		(fp_line
			(start 0.7874 -0.4064)
			(end 0.7874 0.4064)
			(stroke
				(width 0.1524)
				(type default)
			)
			(layer "F.SilkS")
		)
		(fp_line
			(start 0.7874 0.4064)
			(end -0.7874 0.4064)
			(stroke
				(width 0.1524)
				(type default)
			)
			(layer "F.SilkS")
		)
		(fp_line
			(start -0.67945 -0.305054)
			(end -0.12065 -0.305054)
			(stroke
				(width 0.1)
				(type default)
			)
			(layer "F.Fab")
		)
		(fp_line
			(start -0.67945 0.3048)
			(end -0.67945 -0.305054)
			(stroke
				(width 0.1)
				(type default)
			)
			(layer "F.Fab")
		)
		(fp_line
			(start -0.12065 -0.305054)
			(end -0.12065 -0.2794)
			(stroke
				(width 0.1)
				(type default)
			)
			(layer "F.Fab")
		)
		(fp_line
			(start -0.12065 -0.2794)
			(end 0.12065 -0.2794)
			(stroke
				(width 0.1)
				(type default)
			)
			(layer "F.Fab")
		)
		(fp_line
			(start -0.12065 0.2794)
			(end -0.12065 0.3048)
			(stroke
				(width 0.1)
				(type default)
			)
			(layer "F.Fab")
		)
		(fp_line
			(start -0.12065 0.3048)
			(end -0.67945 0.3048)
			(stroke
				(width 0.1)
				(type default)
			)
			(layer "F.Fab")
		)
		(fp_line
			(start 0.120396 0.2794)
			(end -0.12065 0.2794)
			(stroke
				(width 0.1)
				(type default)
			)
			(layer "F.Fab")
		)
		(fp_line
			(start 0.120396 0.3048)
			(end 0.120396 0.2794)
			(stroke
				(width 0.1)
				(type default)
			)
			(layer "F.Fab")
		)
		(fp_line
			(start 0.12065 -0.3048)
			(end 0.67945 -0.3048)
			(stroke
				(width 0.1)
				(type default)
			)
			(layer "F.Fab")
		)
		(fp_line
			(start 0.12065 -0.2794)
			(end 0.12065 -0.3048)
			(stroke
				(width 0.1)
				(type default)
			)
			(layer "F.Fab")
		)
		(fp_line
			(start 0.67945 -0.3048)
			(end 0.67945 0.3048)
			(stroke
				(width 0.1)
				(type default)
			)
			(layer "F.Fab")
		)
		(fp_line
			(start 0.67945 0.3048)
			(end 0.120396 0.3048)
			(stroke
				(width 0.1)
				(type default)
			)
			(layer "F.Fab")
		)
		(pad "1" smd circle
			(at -0.40005 0)
			(size 0 0)
			(layers "F.Cu" "F.Mask" "F.Paste")
			(net "GND")
		)
		(pad "2" smd circle
			(at 0.40005 0)
			(size 0 0)
			(layers "F.Cu" "F.Mask" "F.Paste")
			(net "INA230_7_A0")
		)
	)
	(footprint ""
		(layer "F.Cu")
		(at 21.702268 -423.450258)
		(property "Reference" "C6011"
			(at 0 0 0)
			(layer "F.SilkS")
			(hide yes)
			(effects
				(font
					(size 1.27 1.27)
				)
			)
		)
		(property "Value" ""
			(at 0 0 0)
			(layer "F.Fab")
			(effects
				(font
					(size 1.27 1.27)
				)
			)
		)
		(duplicate_pad_numbers_are_jumpers no)
		(fp_line
			(start -0.7874 -0.4064)
			(end 0.7874 -0.4064)
			(stroke
				(width 0.1524)
				(type default)
			)
			(layer "F.SilkS")
		)
		(fp_line
			(start -0.7874 0.4064)
			(end -0.7874 -0.4064)
			(stroke
				(width 0.1524)
				(type default)
			)
			(layer "F.SilkS")
		)
		(fp_line
			(start 0.7874 -0.4064)
			(end 0.7874 0.4064)
			(stroke
				(width 0.1524)
				(type default)
			)
			(layer "F.SilkS")
		)
		(fp_line
			(start 0.7874 0.4064)
			(end -0.7874 0.4064)
			(stroke
				(width 0.1524)
				(type default)
			)
			(layer "F.SilkS")
		)
		(fp_line
			(start -0.67945 -0.305054)
			(end -0.12065 -0.305054)
			(stroke
				(width 0.1)
				(type default)
			)
			(layer "F.Fab")
		)
		(fp_line
			(start -0.67945 0.3048)
			(end -0.67945 -0.305054)
			(stroke
				(width 0.1)
				(type default)
			)
			(layer "F.Fab")
		)
		(fp_line
			(start -0.12065 -0.305054)
			(end -0.12065 -0.2794)
			(stroke
				(width 0.1)
				(type default)
			)
			(layer "F.Fab")
		)
		(fp_line
			(start -0.12065 -0.2794)
			(end 0.12065 -0.2794)
			(stroke
				(width 0.1)
				(type default)
			)
			(layer "F.Fab")
		)
		(fp_line
			(start -0.12065 0.2794)
			(end -0.12065 0.3048)
			(stroke
				(width 0.1)
				(type default)
			)
			(layer "F.Fab")
		)
		(fp_line
			(start -0.12065 0.3048)
			(end -0.67945 0.3048)
			(stroke
				(width 0.1)
				(type default)
			)
			(layer "F.Fab")
		)
		(fp_line
			(start 0.120396 0.2794)
			(end -0.12065 0.2794)
			(stroke
				(width 0.1)
				(type default)
			)
			(layer "F.Fab")
		)
		(fp_line
			(start 0.120396 0.3048)
			(end 0.120396 0.2794)
			(stroke
				(width 0.1)
				(type default)
			)
			(layer "F.Fab")
		)
		(fp_line
			(start 0.12065 -0.3048)
			(end 0.67945 -0.3048)
			(stroke
				(width 0.1)
				(type default)
			)
			(layer "F.Fab")
		)
		(fp_line
			(start 0.12065 -0.2794)
			(end 0.12065 -0.3048)
			(stroke
				(width 0.1)
				(type default)
			)
			(layer "F.Fab")
		)
		(fp_line
			(start 0.67945 -0.3048)
			(end 0.67945 0.3048)
			(stroke
				(width 0.1)
				(type default)
			)
			(layer "F.Fab")
		)
		(fp_line
			(start 0.67945 0.3048)
			(end 0.120396 0.3048)
			(stroke
				(width 0.1)
				(type default)
			)
			(layer "F.Fab")
		)
		(pad "1" smd circle
			(at -0.40005 0)
			(size 0 0)
			(layers "F.Cu" "F.Mask" "F.Paste")
			(net "BUF2_VDD")
		)
		(pad "2" smd circle
			(at 0.40005 0)
			(size 0 0)
			(layers "F.Cu" "F.Mask" "F.Paste")
			(net "GND")
		)
	)
	(footprint ""
		(layer "F.Cu")
		(at 39.459662 -429.790098 90)
		(property "Reference" "R3292"
			(at 0 0 90)
			(layer "F.SilkS")
			(hide yes)
			(effects
				(font
					(size 1.27 1.27)
				)
			)
		)
		(property "Value" ""
			(at 0 0 90)
			(layer "F.Fab")
			(effects
				(font
					(size 1.27 1.27)
				)
			)
		)
		(duplicate_pad_numbers_are_jumpers no)
		(fp_line
			(start 0.7874 -0.4064)
			(end 0.7874 0.4064)
			(stroke
				(width 0.1524)
				(type default)
			)
			(layer "F.SilkS")
		)
		(fp_line
			(start -0.7874 -0.4064)
			(end 0.7874 -0.4064)
			(stroke
				(width 0.1524)
				(type default)
			)
			(layer "F.SilkS")
		)
		(fp_line
			(start 0.7874 0.4064)
			(end -0.7874 0.4064)
			(stroke
				(width 0.1524)
				(type default)
			)
			(layer "F.SilkS")
		)
		(fp_line
			(start -0.7874 0.4064)
			(end -0.7874 -0.4064)
			(stroke
				(width 0.1524)
				(type default)
			)
			(layer "F.SilkS")
		)
		(fp_line
			(start -0.12065 -0.305054)
			(end -0.12065 -0.2794)
			(stroke
				(width 0.1)
				(type default)
			)
			(layer "F.Fab")
		)
		(fp_line
			(start -0.67945 -0.305054)
			(end -0.12065 -0.305054)
			(stroke
				(width 0.1)
				(type default)
			)
			(layer "F.Fab")
		)
		(fp_line
			(start 0.67945 -0.3048)
			(end 0.67945 0.3048)
			(stroke
				(width 0.1)
				(type default)
			)
			(layer "F.Fab")
		)
		(fp_line
			(start 0.12065 -0.3048)
			(end 0.67945 -0.3048)
			(stroke
				(width 0.1)
				(type default)
			)
			(layer "F.Fab")
		)
		(fp_line
			(start 0.12065 -0.2794)
			(end 0.12065 -0.3048)
			(stroke
				(width 0.1)
				(type default)
			)
			(layer "F.Fab")
		)
		(fp_line
			(start -0.12065 -0.2794)
			(end 0.12065 -0.2794)
			(stroke
				(width 0.1)
				(type default)
			)
			(layer "F.Fab")
		)
		(fp_line
			(start 0.120396 0.2794)
			(end -0.12065 0.2794)
			(stroke
				(width 0.1)
				(type default)
			)
			(layer "F.Fab")
		)
		(fp_line
			(start -0.12065 0.2794)
			(end -0.12065 0.3048)
			(stroke
				(width 0.1)
				(type default)
			)
			(layer "F.Fab")
		)
		(fp_line
			(start 0.67945 0.3048)
			(end 0.120396 0.3048)
			(stroke
				(width 0.1)
				(type default)
			)
			(layer "F.Fab")
		)
		(fp_line
			(start 0.120396 0.3048)
			(end 0.120396 0.2794)
			(stroke
				(width 0.1)
				(type default)
			)
			(layer "F.Fab")
		)
		(fp_line
			(start -0.12065 0.3048)
			(end -0.67945 0.3048)
			(stroke
				(width 0.1)
				(type default)
			)
			(layer "F.Fab")
		)
		(fp_line
			(start -0.67945 0.3048)
			(end -0.67945 -0.305054)
			(stroke
				(width 0.1)
				(type default)
			)
			(layer "F.Fab")
		)
		(pad "1" smd circle
			(at -0.40005 0 90)
			(size 0 0)
			(layers "F.Cu" "F.Mask" "F.Paste")
			(net "P3V3_AUX")
		)
		(pad "2" smd circle
			(at 0.40005 0 90)
			(size 0 0)
			(layers "F.Cu" "F.Mask" "F.Paste")
			(net "CLK_GEN2_GPU_FPGA_OE_OR_N")
		)
	)
)
